(kicad_pcb
	(version 20260206)
	(generator "pcbnew")
	(generator_version "10.0")
	(general
		(thickness 1.6)
		(legacy_teardrops no)
	)
	(paper "A4")
	(title_block
		(title "peb — Lightning_PEB_BRD.brd")
		(comment 1 "Lightning (Wiwynn / Facebook NVMe JBOF) / footprints 849-855 of 2563")
	)
	(layers
		(0 "F.Cu" signal "TOP")
		(4 "In1.Cu" signal "L2GND")
		(6 "In2.Cu" signal "L3")
		(8 "In3.Cu" signal "L4VCC")
		(10 "In4.Cu" signal "L5VCC")
		(12 "In5.Cu" signal "L6")
		(14 "In6.Cu" signal "L7GND")
		(2 "B.Cu" signal "BOTTOM")
		(9 "F.Adhes" user "F.Adhesive")
		(11 "B.Adhes" user "B.Adhesive")
		(13 "F.Paste" user "Package Geometry/Pastemask Top")
		(15 "B.Paste" user "Package Geometry/Pastemask Bottom")
		(5 "F.SilkS" user "Ref Des/Silkscreen Top")
		(7 "B.SilkS" user "Ref Des/Silkscreen Bottom")
		(1 "F.Mask" user "Board Geometry/Soldermask Top")
		(3 "B.Mask" user "Board Geometry/Soldermask Bottom")
		(17 "Dwgs.User" user "User.Drawings")
		(19 "Cmts.User" user "User.Comments")
		(21 "Eco1.User" user "User.Eco1")
		(23 "Eco2.User" user "User.Eco2")
		(25 "Edge.Cuts" user "Board Geometry/Outline")
		(27 "Margin" user)
		(31 "F.CrtYd" user "Package Geometry/Place Bound Top")
		(29 "B.CrtYd" user "Package Geometry/Place Bound Bottom")
		(35 "F.Fab" user "Ref Des/Assembly Top")
		(33 "B.Fab" user "Ref Des/Assembly Bottom")
	)
	(footprint ""
		(layer "F.Cu")
		(at 166.116 -94.5134 90)
		(property "Reference" "R88"
			(at 0 0 90)
			(layer "F.SilkS")
			(hide yes)
			(effects
				(font
					(size 1.27 1.27)
				)
			)
		)
		(property "Value" "0R2J-2-GP"
			(at 0.064008 -3.993896 90)
			(unlocked yes)
			(layer "F.Fab")
			(hide yes)
			(effects
				(font
					(size 1.016 1.016)
					(thickness 0.1524)
				)
			)
		)
		(property "Device Type" "R402H16"
			(at 0.064008 -5.517896 90)
			(unlocked yes)
			(layer "F.Fab")
			(hide yes)
			(effects
				(font
					(size 1.016 1.016)
					(thickness 0.1524)
				)
			)
		)
		(duplicate_pad_numbers_are_jumpers no)
		(fp_line
			(start 0.508 -0.9398)
			(end -0.508 -0.9398)
			(stroke
				(width 0.1524)
				(type default)
			)
			(layer "F.SilkS")
		)
		(fp_line
			(start -0.508 -0.9398)
			(end -0.508 0.9398)
			(stroke
				(width 0.1524)
				(type default)
			)
			(layer "F.SilkS")
		)
		(fp_rect
			(start -0.508 0.9398)
			(end 0.508 -0.9398)
			(stroke
				(width 0)
				(type default)
			)
			(fill no)
			(layer "F.CrtYd")
		)
		(fp_rect
			(start -0.508 0.9398)
			(end 0.508 -0.9398)
			(stroke
				(width 0)
				(type default)
			)
			(fill no)
			(layer "F.Fab")
		)
		(pad "1" smd custom
			(at 0 -0.4445 90)
			(size 0.1397 0.1397)
			(layers "F.Cu" "F.Mask" "F.Paste")
			(net "CLKGEN_OE2_R")
			(options
				(clearance outline)
				(anchor circle)
			)
			(primitives
				(gr_poly
					(pts
						(arc
							(start -0.1778 -0.2794)
							(mid -0.249642 -0.249642)
							(end -0.2794 -0.1778)
						)
						(arc
							(start -0.2794 0.1778)
							(mid -0.249642 0.249642)
							(end -0.1778 0.2794)
						)
						(arc
							(start 0.1778 0.2794)
							(mid 0.249642 0.249642)
							(end 0.2794 0.1778)
						)
						(arc
							(start 0.2794 -0.1778)
							(mid 0.249642 -0.249642)
							(end 0.1778 -0.2794)
						)
					)
					(width 0)
					(fill yes)
				)
			)
		)
		(pad "2" smd custom
			(at 0 0.4445 90)
			(size 0.1397 0.1397)
			(layers "F.Cu" "F.Mask" "F.Paste")
			(net "CLKGEN_OE2")
			(options
				(clearance outline)
				(anchor circle)
			)
			(primitives
				(gr_poly
					(pts
						(arc
							(start -0.1778 -0.2794)
							(mid -0.249642 -0.249642)
							(end -0.2794 -0.1778)
						)
						(arc
							(start -0.2794 0.1778)
							(mid -0.249642 0.249642)
							(end -0.1778 0.2794)
						)
						(arc
							(start 0.1778 0.2794)
							(mid 0.249642 0.249642)
							(end 0.2794 0.1778)
						)
						(arc
							(start 0.2794 -0.1778)
							(mid 0.249642 -0.249642)
							(end 0.1778 -0.2794)
						)
					)
					(width 0)
					(fill yes)
				)
			)
		)
	)
	(footprint ""
		(layer "F.Cu")
		(at 169.037 -53.848 -90)
		(property "Reference" "R326"
			(at 0 0 270)
			(layer "F.SilkS")
			(hide yes)
			(effects
				(font
					(size 1.27 1.27)
				)
			)
		)
		(property "Value" "0R2J-2-GP"
			(at 0.064008 -3.993896 270)
			(unlocked yes)
			(layer "F.Fab")
			(hide yes)
			(effects
				(font
					(size 1.016 1.016)
					(thickness 0.1524)
				)
			)
		)
		(property "Device Type" "R402H16"
			(at 0.064008 -5.517896 270)
			(unlocked yes)
			(layer "F.Fab")
			(hide yes)
			(effects
				(font
					(size 1.016 1.016)
					(thickness 0.1524)
				)
			)
		)
		(duplicate_pad_numbers_are_jumpers no)
		(fp_line
			(start -0.508 -0.9398)
			(end -0.508 0.9398)
			(stroke
				(width 0.1524)
				(type default)
			)
			(layer "F.SilkS")
		)
		(fp_line
			(start 0.508 -0.9398)
			(end -0.508 -0.9398)
			(stroke
				(width 0.1524)
				(type default)
			)
			(layer "F.SilkS")
		)
		(fp_rect
			(start -0.508 0.9398)
			(end 0.508 -0.9398)
			(stroke
				(width 0)
				(type default)
			)
			(fill no)
			(layer "F.CrtYd")
		)
		(fp_rect
			(start -0.508 0.9398)
			(end 0.508 -0.9398)
			(stroke
				(width 0)
				(type default)
			)
			(fill no)
			(layer "F.Fab")
		)
		(pad "1" smd custom
			(at 0 -0.4445 270)
			(size 0.1397 0.1397)
			(layers "F.Cu" "F.Mask" "F.Paste")
			(net "VS1_LED_R")
			(options
				(clearance outline)
				(anchor circle)
			)
			(primitives
				(gr_poly
					(pts
						(arc
							(start -0.1778 -0.2794)
							(mid -0.249642 -0.249642)
							(end -0.2794 -0.1778)
						)
						(arc
							(start -0.2794 0.1778)
							(mid -0.249642 0.249642)
							(end -0.1778 0.2794)
						)
						(arc
							(start 0.1778 0.2794)
							(mid 0.249642 0.249642)
							(end 0.2794 0.1778)
						)
						(arc
							(start 0.2794 -0.1778)
							(mid 0.249642 -0.249642)
							(end 0.1778 -0.2794)
						)
					)
					(width 0)
					(fill yes)
				)
			)
		)
		(pad "2" smd custom
			(at 0 0.4445 270)
			(size 0.1397 0.1397)
			(layers "F.Cu" "F.Mask" "F.Paste")
			(net "VS1_LED")
			(options
				(clearance outline)
				(anchor circle)
			)
			(primitives
				(gr_poly
					(pts
						(arc
							(start -0.1778 -0.2794)
							(mid -0.249642 -0.249642)
							(end -0.2794 -0.1778)
						)
						(arc
							(start -0.2794 0.1778)
							(mid -0.249642 0.249642)
							(end -0.1778 0.2794)
						)
						(arc
							(start 0.1778 0.2794)
							(mid 0.249642 0.249642)
							(end 0.2794 0.1778)
						)
						(arc
							(start 0.2794 -0.1778)
							(mid 0.249642 -0.249642)
							(end 0.1778 -0.2794)
						)
					)
					(width 0)
					(fill yes)
				)
			)
		)
	)
	(footprint ""
		(layer "F.Cu")
		(at 24.60244 -125.782578)
		(property "Reference" "R73"
			(at 0 0 0)
			(layer "F.SilkS")
			(hide yes)
			(effects
				(font
					(size 1.27 1.27)
				)
			)
		)
		(property "Value" "33R1J-GP"
			(at -3.3274 -1.3335 0)
			(unlocked yes)
			(layer "F.Fab")
			(hide yes)
			(effects
				(font
					(size 1.016 1.016)
					(thickness 0.1524)
				)
			)
		)
		(property "Device Type" "R0201H12"
			(at -3.3274 -2.8575 0)
			(unlocked yes)
			(layer "F.Fab")
			(hide yes)
			(effects
				(font
					(size 1.016 1.016)
					(thickness 0.1524)
				)
			)
		)
		(duplicate_pad_numbers_are_jumpers no)
		(fp_rect
			(start -0.2794 0.6477)
			(end 0.2794 -0.6477)
			(stroke
				(width 0)
				(type default)
			)
			(fill no)
			(layer "F.CrtYd")
		)
		(fp_rect
			(start -0.2794 0.6477)
			(end 0.2794 -0.6477)
			(stroke
				(width 0)
				(type default)
			)
			(fill no)
			(layer "F.Fab")
		)
		(pad "1" smd custom
			(at 0 -0.2794)
			(size 0.0762 0.0762)
			(layers "F.Cu" "F.Mask" "F.Paste")
			(net "BMC_REFCLK_N")
			(options
				(clearance outline)
				(anchor circle)
			)
			(primitives
				(gr_poly
					(pts
						(arc
							(start 0.1524 -0.127)
							(mid 0.137521 -0.162921)
							(end 0.1016 -0.1778)
						)
						(arc
							(start -0.1016 -0.1778)
							(mid -0.137521 -0.162921)
							(end -0.1524 -0.127)
						)
						(arc
							(start -0.1524 0.127)
							(mid -0.137521 0.162921)
							(end -0.1016 0.1778)
						)
						(arc
							(start 0.1016 0.1778)
							(mid 0.137521 0.162921)
							(end 0.1524 0.127)
						)
					)
					(width 0)
					(fill yes)
				)
			)
		)
		(pad "2" smd custom
			(at 0 0.2794)
			(size 0.0762 0.0762)
			(layers "F.Cu" "F.Mask" "F.Paste")
			(net "BMC_REFCLK_P")
			(options
				(clearance outline)
				(anchor circle)
			)
			(primitives
				(gr_poly
					(pts
						(arc
							(start 0.1524 -0.127)
							(mid 0.137521 -0.162921)
							(end 0.1016 -0.1778)
						)
						(arc
							(start -0.1016 -0.1778)
							(mid -0.137521 -0.162921)
							(end -0.1524 -0.127)
						)
						(arc
							(start -0.1524 0.127)
							(mid -0.137521 0.162921)
							(end -0.1016 0.1778)
						)
						(arc
							(start 0.1016 0.1778)
							(mid 0.137521 0.162921)
							(end 0.1524 0.127)
						)
					)
					(width 0)
					(fill yes)
				)
			)
		)
	)
	(footprint ""
		(layer "F.Cu")
		(at 17.78 -157.48 180)
		(property "Reference" "D1402"
			(at 0 0 180)
			(layer "F.SilkS")
			(hide yes)
			(effects
				(font
					(size 1.27 1.27)
				)
			)
		)
		(property "Value" "RB551V30-GP"
			(at 0 -6.7818 180)
			(unlocked yes)
			(layer "F.Fab")
			(hide yes)
			(effects
				(font
					(size 1.016 1.016)
					(thickness 0.1524)
				)
			)
		)
		(property "Device Type" "SOD323AKH38"
			(at 0 -8.6868 180)
			(unlocked yes)
			(layer "F.Fab")
			(hide yes)
			(effects
				(font
					(size 1.016 1.016)
					(thickness 0.1524)
				)
			)
		)
		(duplicate_pad_numbers_are_jumpers no)
		(fp_line
			(start 0.889 2.159)
			(end -0.889 2.159)
			(stroke
				(width 0.1524)
				(type default)
			)
			(layer "F.SilkS")
		)
		(fp_line
			(start 0.889 -1.9304)
			(end 0.889 2.159)
			(stroke
				(width 0.1524)
				(type default)
			)
			(layer "F.SilkS")
		)
		(fp_line
			(start 0.762 2.0574)
			(end -0.762 2.0574)
			(stroke
				(width 0.508)
				(type default)
			)
			(layer "F.SilkS")
		)
		(fp_line
			(start -0.889 2.159)
			(end -0.889 -1.9304)
			(stroke
				(width 0.1524)
				(type default)
			)
			(layer "F.SilkS")
		)
		(fp_line
			(start -0.889 -1.9304)
			(end 0.889 -1.9304)
			(stroke
				(width 0.1524)
				(type default)
			)
			(layer "F.SilkS")
		)
		(fp_rect
			(start -1.016 2.3114)
			(end 1.016 -2.0066)
			(stroke
				(width 0)
				(type default)
			)
			(fill no)
			(layer "F.CrtYd")
		)
		(fp_poly
			(pts
				(xy -1.016 -2.0066) (xy 1.016 -2.0066) (xy 1.016 2.3114) (xy -1.016 2.3114)
			)
			(stroke
				(width 0)
				(type default)
			)
			(fill no)
			(layer "F.Fab")
		)
		(pad "A" smd rect
			(at 0 -1.143 180)
			(size 0.5588 1.016)
			(layers "F.Cu" "F.Mask" "F.Paste")
			(net "FM_BMC_RESET#_BTN_D")
		)
		(pad "K" smd rect
			(at 0 1.143 180)
			(size 0.5588 1.016)
			(layers "F.Cu" "F.Mask" "F.Paste")
			(net "FM_BMC_RESET#_BTN")
		)
	)
	(footprint ""
		(layer "F.Cu")
		(at 122.143774 -35.131756 180)
		(property "Reference" "R619"
			(at 0 0 180)
			(layer "F.SilkS")
			(hide yes)
			(effects
				(font
					(size 1.27 1.27)
				)
			)
		)
		(property "Value" "0R2J-2-GP"
			(at 0.064008 -3.993896 180)
			(unlocked yes)
			(layer "F.Fab")
			(hide yes)
			(effects
				(font
					(size 1.016 1.016)
					(thickness 0.1524)
				)
			)
		)
		(property "Device Type" "R402H16"
			(at 0.064008 -5.517896 180)
			(unlocked yes)
			(layer "F.Fab")
			(hide yes)
			(effects
				(font
					(size 1.016 1.016)
					(thickness 0.1524)
				)
			)
		)
		(duplicate_pad_numbers_are_jumpers no)
		(fp_line
			(start 0.508 -0.9398)
			(end -0.508 -0.9398)
			(stroke
				(width 0.1524)
				(type default)
			)
			(layer "F.SilkS")
		)
		(fp_line
			(start -0.508 -0.9398)
			(end -0.508 0.9398)
			(stroke
				(width 0.1524)
				(type default)
			)
			(layer "F.SilkS")
		)
		(fp_rect
			(start -0.508 0.9398)
			(end 0.508 -0.9398)
			(stroke
				(width 0)
				(type default)
			)
			(fill no)
			(layer "F.CrtYd")
		)
		(fp_rect
			(start -0.508 0.9398)
			(end 0.508 -0.9398)
			(stroke
				(width 0)
				(type default)
			)
			(fill no)
			(layer "F.Fab")
		)
		(pad "1" smd custom
			(at 0 -0.4445 180)
			(size 0.1397 0.1397)
			(layers "F.Cu" "F.Mask" "F.Paste")
			(net "UPLINK1_R")
			(options
				(clearance outline)
				(anchor circle)
			)
			(primitives
				(gr_poly
					(pts
						(arc
							(start -0.1778 -0.2794)
							(mid -0.249642 -0.249642)
							(end -0.2794 -0.1778)
						)
						(arc
							(start -0.2794 0.1778)
							(mid -0.249642 0.249642)
							(end -0.1778 0.2794)
						)
						(arc
							(start 0.1778 0.2794)
							(mid 0.249642 0.249642)
							(end 0.2794 0.1778)
						)
						(arc
							(start 0.2794 -0.1778)
							(mid 0.249642 -0.249642)
							(end 0.1778 -0.2794)
						)
					)
					(width 0)
					(fill yes)
				)
			)
		)
		(pad "2" smd custom
			(at 0 0.4445 180)
			(size 0.1397 0.1397)
			(layers "F.Cu" "F.Mask" "F.Paste")
			(net "UPLINK1")
			(options
				(clearance outline)
				(anchor circle)
			)
			(primitives
				(gr_poly
					(pts
						(arc
							(start -0.1778 -0.2794)
							(mid -0.249642 -0.249642)
							(end -0.2794 -0.1778)
						)
						(arc
							(start -0.2794 0.1778)
							(mid -0.249642 0.249642)
							(end -0.1778 0.2794)
						)
						(arc
							(start 0.1778 0.2794)
							(mid 0.249642 0.249642)
							(end 0.2794 0.1778)
						)
						(arc
							(start 0.2794 -0.1778)
							(mid 0.249642 -0.249642)
							(end 0.1778 -0.2794)
						)
					)
					(width 0)
					(fill yes)
				)
			)
		)
	)
	(footprint ""
		(layer "F.Cu")
		(at 83.627214 -83.04022 180)
		(property "Reference" "SC1303"
			(at 0 0 180)
			(layer "F.SilkS")
			(hide yes)
			(effects
				(font
					(size 1.27 1.27)
				)
			)
		)
		(property "Value" "SCD1U16V2KX-3GP"
			(at 1.1811 -2.7051 180)
			(unlocked yes)
			(layer "F.Fab")
			(hide yes)
			(effects
				(font
					(size 1.016 1.016)
					(thickness 0.1524)
				)
			)
		)
		(property "Device Type" "C402H22"
			(at 1.1811 -4.2291 180)
			(unlocked yes)
			(layer "F.Fab")
			(hide yes)
			(effects
				(font
					(size 1.016 1.016)
					(thickness 0.1524)
				)
			)
		)
		(duplicate_pad_numbers_are_jumpers no)
		(fp_rect
			(start -0.4318 0.9525)
			(end 0.4318 -0.9525)
			(stroke
				(width 0)
				(type default)
			)
			(fill no)
			(layer "F.CrtYd")
		)
		(fp_rect
			(start -0.4318 0.9525)
			(end 0.4318 -0.9525)
			(stroke
				(width 0)
				(type default)
			)
			(fill no)
			(layer "F.Fab")
		)
		(pad "1" smd custom
			(at 0 -0.4445 180)
			(size 0.1524 0.1524)
			(layers "F.Cu" "F.Mask" "F.Paste")
			(net "P1V8_STBY")
			(options
				(clearance outline)
				(anchor circle)
			)
			(primitives
				(gr_poly
					(pts
						(arc
							(start 0.3048 -0.2032)
							(mid 0.275042 -0.275042)
							(end 0.2032 -0.3048)
						)
						(arc
							(start -0.2032 -0.3048)
							(mid -0.275042 -0.275042)
							(end -0.3048 -0.2032)
						)
						(arc
							(start -0.3048 0.2032)
							(mid -0.275042 0.275042)
							(end -0.2032 0.3048)
						)
						(arc
							(start 0.2032 0.3048)
							(mid 0.275042 0.275042)
							(end 0.3048 0.2032)
						)
					)
					(width 0)
					(fill yes)
				)
			)
		)
		(pad "2" smd custom
			(at 0 0.4445 180)
			(size 0.1524 0.1524)
			(layers "F.Cu" "F.Mask" "F.Paste")
			(net "GND")
			(options
				(clearance outline)
				(anchor circle)
			)
			(primitives
				(gr_poly
					(pts
						(arc
							(start 0.3048 -0.2032)
							(mid 0.275042 -0.275042)
							(end 0.2032 -0.3048)
						)
						(arc
							(start -0.2032 -0.3048)
							(mid -0.275042 -0.275042)
							(end -0.3048 -0.2032)
						)
						(arc
							(start -0.3048 0.2032)
							(mid -0.275042 0.275042)
							(end -0.2032 0.3048)
						)
						(arc
							(start 0.2032 0.3048)
							(mid 0.275042 0.275042)
							(end 0.3048 0.2032)
						)
					)
					(width 0)
					(fill yes)
				)
			)
		)
	)
	(footprint ""
		(layer "F.Cu")
		(at 193.6242 -4.1148)
		(property "Reference" "JP12"
			(at 0 0 0)
			(layer "F.SilkS")
			(hide yes)
			(effects
				(font
					(size 1.27 1.27)
				)
			)
		)
		(property "Value" "PIN-CON3-S-GP"
			(at -5.588 -5.3086 0)
			(unlocked yes)
			(layer "F.Fab")
			(hide yes)
			(effects
				(font
					(size 1.016 1.016)
					(thickness 0.1524)
				)
			)
		)
		(property "Device Type" "21S-91-03GB01"
			(at -5.588 -6.8326 0)
			(unlocked yes)
			(layer "F.Fab")
			(hide yes)
			(effects
				(font
					(size 1.016 1.016)
					(thickness 0.1524)
				)
			)
		)
		(duplicate_pad_numbers_are_jumpers no)
		(fp_line
			(start -4.0132 -1.6256)
			(end -2.7432 -1.6256)
			(stroke
				(width 0.4064)
				(type default)
			)
			(layer "F.SilkS")
		)
		(fp_line
			(start -4.0132 -0.3556)
			(end -4.0132 -1.6256)
			(stroke
				(width 0.4064)
				(type default)
			)
			(layer "F.SilkS")
		)
		(fp_line
			(start -3.8862 -1.4986)
			(end -3.8862 1.4986)
			(stroke
				(width 0.1524)
				(type default)
			)
			(layer "F.SilkS")
		)
		(fp_line
			(start -3.8862 1.4986)
			(end 3.8862 1.4986)
			(stroke
				(width 0.1524)
				(type default)
			)
			(layer "F.SilkS")
		)
		(fp_line
			(start 3.8862 -1.4986)
			(end -3.8862 -1.4986)
			(stroke
				(width 0.1524)
				(type default)
			)
			(layer "F.SilkS")
		)
		(fp_line
			(start 3.8862 1.4986)
			(end 3.8862 -1.4986)
			(stroke
				(width 0.1524)
				(type default)
			)
			(layer "F.SilkS")
		)
		(fp_circle
			(center -2.54 0)
			(end -1.4732 0)
			(stroke
				(width 0.3048)
				(type default)
			)
			(fill no)
			(layer "F.SilkS")
		)
		(fp_circle
			(center 0 0)
			(end 1.0668 0)
			(stroke
				(width 0.3048)
				(type default)
			)
			(fill no)
			(layer "F.SilkS")
		)
		(fp_circle
			(center 2.54 0)
			(end 3.6068 0)
			(stroke
				(width 0.3048)
				(type default)
			)
			(fill no)
			(layer "F.SilkS")
		)
		(fp_rect
			(start -3.6322 1.2446)
			(end 3.6322 -1.2446)
			(stroke
				(width 0)
				(type default)
			)
			(fill no)
			(layer "F.CrtYd")
		)
		(fp_poly
			(pts
				(xy 4.1402 -1.2446) (xy -3.6322 -1.2446) (xy -3.6322 1.2446) (xy 3.6322 1.2446) (xy 3.6322 -1.2319)
				(xy 4.1402 -1.2319) (xy 4.1402 1.7526) (xy -4.1402 1.7526) (xy -4.1402 -1.7526) (xy 4.1402 -1.7526)
			)
			(stroke
				(width 0)
				(type default)
			)
			(fill no)
			(layer "F.CrtYd")
		)
		(fp_rect
			(start -4.1402 1.7526)
			(end 4.1402 -1.7526)
			(stroke
				(width 0)
				(type default)
			)
			(fill no)
			(layer "F.Fab")
		)
		(pad "1" thru_hole circle
			(at -2.54 0)
			(size 1.4224 1.4224)
			(drill 1.016)
			(layers "*.Cu" "*.Mask")
			(remove_unused_layers no)
			(net "WP_DISABLE")
			(clearance 0.1524)
			(thermal_gap 0.1524)
		)
		(pad "2" thru_hole circle
			(at 0 0)
			(size 1.4224 1.4224)
			(drill 1.016)
			(layers "*.Cu" "*.Mask")
			(remove_unused_layers no)
			(net "FLA1_WPN")
			(clearance 0.1524)
			(thermal_gap 0.1524)
		)
		(pad "3" thru_hole circle
			(at 2.54 0)
			(size 1.4224 1.4224)
			(drill 1.016)
			(layers "*.Cu" "*.Mask")
			(remove_unused_layers no)
			(net "WP_ENABLE")
			(clearance 0.1524)
			(thermal_gap 0.1524)
		)
	)
)
